(kicad_sch
	(version 20250114)
	(generator "eeschema")
	(generator_version "9.0")
	(paper "A3")
	(title_block
		(title "Kintex 410T devboard")
		(date "2024-04-03")
		(rev "1.1.2")
	)
	(bus_alias "CLK"
		(members "CLK_N" "CLK_P")
	)
	(bus_alias "CW-20PIN"
		(members "HS[1..2]" "IO[1..4]" "RST" "MISO" "MOSI" "TSCK" "TPDIC" "TPDID")
	)
	(bus_alias "DDR3_DRAM"
		(members "A[0..15]" "BA[0..2]" "DQ[0..7]" "DQS_P" "DQS_N" "TDQS_P" "TDQS_N"
			"~{WE}" "~{CAS}" "~{RAS}" "~{CS}" "CKE" "CK_N" "CK_P" "ODT" "~{RESET}"
			"DM"
		)
	)
	(bus_alias "FMC-CTRL"
		(members "CLK_DIR" "PRSNT_M2C" "~{PERST}")
	)
	(bus_alias "FMC-IO"
		(members "IO0" "IO1_N" "IO1_P" "IO2_N" "IO2_P" "IO3_N" "IO3_P" "IO4_N"
			"IO4_P" "IO5_N" "IO5_P" "IO6_N" "IO6_P" "IO7_N" "IO7_P" "IO8_N" "IO8_P"
			"IO9_N" "IO9_P" "IO10_N" "IO10_P" "IO11_N" "IO11_P" "IO12_N" "IO12_P"
			"IO13_N" "IO13_P" "IO14_N" "IO14_P" "IO15_N" "IO15_P" "IO16_N" "IO16_P"
			"IO17_N" "IO17_P" "IO18_N" "IO18_P" "IO19_N" "IO19_P" "IO20_N" "IO20_P"
			"IO21_N" "IO21_P" "IO22_N" "IO22_P" "IO23_N" "IO23_P" "IO24_N" "IO24_P"
			"IO25"
		)
	)
	(bus_alias "HDMI"
		(members "D0_P" "D0_N" "D1_P" "D1_N" "D2_P" "D2_N" "CLK_P" "CLK_N" "CEC"
			"HPD" "UTL" "SDA" "SCL"
		)
	)
	(bus_alias "I2C"
		(members "SDA" "SCL" "QDCDC1_SCL" "QDCDC2_SCL")
	)
	(bus_alias "JTAG"
		(members "TMS" "TCK" "TDI" "TDO" "RST")
	)
	(bus_alias "MGTX"
		(members "TX0_P" "TX1_P" "TX2_P" "TX3_P" "TX0_n" "TX0_N" "TX1_N" "TX2_N"
			"TX3_N" "RX0_P" "RX1_P" "RX2_P" "RX3_P" "RX0_N" "RX1_N" "RX2_N" "RX3_N"
			"REFCLK0_P" "REFCLK0_N" "REFCLK1_P" "REFCLK1_N"
		)
	)
	(bus_alias "PB-CTRL"
		(members "~{PB_CTRL_CLR}" "VDDR_EN" "~{PB_CTRL_INT}")
	)
	(bus_alias "PLL-CLK"
		(members "CLK0" "CLK1" "CLK2")
	)
	(bus_alias "PMOD"
		(members "IO[1..4]" "IO[7..10]")
	)
	(bus_alias "POE"
		(members "VC[1..4]")
	)
	(bus_alias "RGMII"
		(members "~{RESET}" "MDC" "MDIO" "TX_EN" "TXD[0..3]" "RXD[0..3]" "RX_DV"
			"GTX_CLK" "GTR_CLK" "REFCLK" "~{INT}"
		)
	)
	(bus_alias "RMII"
		(members "RXD0" "RXD1" "TXD0" "TXD1" "~{RESET}" "~{INT}" "MDIO" "MDC" "TXEN"
			"RX_DV" "RXER" "REFCLK"
		)
	)
	(bus_alias "SD-CARD"
		(members "DAT[0..3]" "~{CD}" "CLK" "CMD")
	)
	(bus_alias "SPI"
		(members "~{RESET}" "SCK" "~{CS}" "MISO" "MOSI" "INT")
	)
	(bus_alias "SPI-FLASH"
		(members "~{CS}" "DQ[0..3]" "~{WP}" "~{HOLD}" "CLK")
	)
	(bus_alias "SPI-USB"
		(members "GPX" "~{RESET}" "~{CS}" "CLK" "MISO" "MOSI" "INT" "VBUS_PEN")
	)
	(bus_alias "SRAM"
		(members "A[0..19]" "DQ[0..7]" "CE2" "~{CE}" "~{WE}" "~{OE}" "SCL" "SDA")
	)
	(bus_alias "STUSB4500"
		(members "RESET" "SCL" "SDA" "~{ALERT}" "ATTACH" "GPIO" "A_B_SIDE")
	)
	(bus_alias "SUP-MCU"
		(members "SDA" "SCL" "PD_RST" "SW_STATE" "PG_VCCINT" "PG_1V8" "PG_1V2"
			"PG_3V3" "FAN_PWM" "SPARE[0..3]" "A[0..19]" "D[0..7]" "WR" "TX[0..1]"
			"ALE" "CE" "CLKO" "RX[0..1]" "RD" "FPGA_M[0..2]" "CCLK" "PROGRAMB" "INITB"
			"DONE" "TEMP_ALERT_N" "FPGA_MISO" "FPGA_MOSI" "MISO" "MOSI" "SCLK[0..1]"
			"~{SCS}" "CFG_CS" "PWR_RST" "PWR_ON"
		)
	)
	(bus_alias "UART"
		(members "TX" "RX")
	)
	(bus_alias "USB-C-PD"
		(members "CC1" "CC2" "VBUS")
	)
	(bus_alias "USB-FPGA-PHY"
		(members "~{OE}" "SUS" "SPD" "VM" "VP" "VPO" "VMO" "RCV" "SCON" "VDET"
			"VBUS_PEN"
		)
	)
	(bus_alias "USER-IO"
		(members "LED_GREEN[0..5]" "LED_BLUE" "LED_RED" "DIP_SW[0..7]" "BUTTON[0..3]"
			"A[1..40]" "B[1..34]"
		)
	)
	(rectangle
		(start 180.34 55.245)
		(end 284.48 240.665)
		(stroke
			(width 0)
			(type dash)
		)
		(fill
			(type none)
		)
	)
	(text "FPGA"
		(exclude_from_sim no)
		(at 180.975 52.705 0)
		(effects
			(font
				(size 2.54 2.54)
				(thickness 0.5)
				(bold yes)
			)
			(justify left bottom)
		)
	)
	(junction
		(at 26.67 232.41)
		(diameter 0)
		(color 0 0 0 0)
	)
	(junction
		(at 137.16 139.065)
		(diameter 0)
		(color 0 0 0 0)
	)
	(junction
		(at 151.13 67.31)
		(diameter 0)
		(color 0 0 0 0)
	)
	(junction
		(at 160.02 130.175)
		(diameter 0)
		(color 0 0 0 0)
	)
	(junction
		(at 26.67 252.73)
		(diameter 0)
		(color 0 0 0 0)
	)
	(junction
		(at 304.165 117.475)
		(diameter 0)
		(color 0 0 0 0)
	)
	(junction
		(at 289.56 186.055)
		(diameter 0)
		(color 0 0 0 0)
	)
	(junction
		(at 304.165 111.125)
		(diameter 0)
		(color 0 0 0 0)
	)
	(junction
		(at 292.735 162.56)
		(diameter 0)
		(color 0 0 0 0)
	)
	(junction
		(at 169.545 111.76)
		(diameter 0)
		(color 0 0 0 0)
	)
	(junction
		(at 151.13 84.455)
		(diameter 0)
		(color 0 0 0 0)
	)
	(junction
		(at 26.67 242.57)
		(diameter 0)
		(color 0 0 0 0)
	)
	(no_connect
		(at 69.85 39.37)
	)
	(bus
		(pts
			(xy 160.02 109.22) (xy 160.02 130.175)
		)
		(stroke
			(width 0)
			(type default)
		)
	)
	(wire
		(pts
			(xy 26.67 232.41) (xy 29.21 232.41)
		)
		(stroke
			(width 0)
			(type default)
		)
	)
	(bus
		(pts
			(xy 151.13 84.455) (xy 181.61 84.455)
		)
		(stroke
			(width 0)
			(type default)
		)
	)
	(bus
		(pts
			(xy 133.35 195.58) (xy 215.9 195.58)
		)
		(stroke
			(width 0)
			(type default)
		)
	)
	(bus
		(pts
			(xy 160.02 130.175) (xy 181.61 130.175)
		)
		(stroke
			(width 0)
			(type default)
		)
	)
	(bus
		(pts
			(xy 171.45 149.86) (xy 171.45 187.96)
		)
		(stroke
			(width 0)
			(type default)
		)
	)
	(bus
		(pts
			(xy 172.72 64.77) (xy 151.13 64.77)
		)
		(stroke
			(width 0)
			(type default)
		)
	)
	(bus
		(pts
			(xy 304.165 111.125) (xy 333.375 111.125)
		)
		(stroke
			(width 0)
			(type default)
		)
	)
	(wire
		(pts
			(xy 26.67 222.25) (xy 29.21 222.25)
		)
		(stroke
			(width 0)
			(type default)
		)
	)
	(wire
		(pts
			(xy 53.34 184.15) (xy 53.34 186.69)
		)
		(stroke
			(width 0)
			(type default)
		)
	)
	(bus
		(pts
			(xy 19.05 191.77) (xy 19.05 44.45)
		)
		(stroke
			(width 0)
			(type default)
		)
	)
	(bus
		(pts
			(xy 133.35 38.1) (xy 154.94 38.1)
		)
		(stroke
			(width 0)
			(type default)
		)
	)
	(bus
		(pts
			(xy 316.23 215.265) (xy 302.26 215.265)
		)
		(stroke
			(width 0)
			(type default)
		)
	)
	(bus
		(pts
			(xy 283.21 111.125) (xy 304.165 111.125)
		)
		(stroke
			(width 0)
			(type default)
		)
	)
	(bus
		(pts
			(xy 169.545 111.76) (xy 181.61 111.76)
		)
		(stroke
			(width 0)
			(type default)
		)
	)
	(bus
		(pts
			(xy 283.21 195.58) (xy 316.23 195.58)
		)
		(stroke
			(width 0)
			(type default)
		)
	)
	(bus
		(pts
			(xy 292.735 162.56) (xy 360.045 162.56)
		)
		(stroke
			(width 0)
			(type default)
		)
	)
	(bus
		(pts
			(xy 162.56 105.41) (xy 181.61 105.41)
		)
		(stroke
			(width 0)
			(type default)
		)
	)
	(bus
		(pts
			(xy 181.61 64.77) (xy 175.26 64.77)
		)
		(stroke
			(width 0)
			(type default)
		)
	)
	(bus
		(pts
			(xy 283.21 179.07) (xy 289.56 179.07)
		)
		(stroke
			(width 0)
			(type default)
		)
	)
	(bus
		(pts
			(xy 133.35 101.6) (xy 181.61 101.6)
		)
		(stroke
			(width 0)
			(type default)
		)
	)
	(bus
		(pts
			(xy 283.21 217.805) (xy 316.23 217.805)
		)
		(stroke
			(width 0)
			(type default)
		)
	)
	(bus
		(pts
			(xy 292.735 123.825) (xy 292.735 162.56)
		)
		(stroke
			(width 0)
			(type default)
		)
	)
	(bus
		(pts
			(xy 133.35 166.37) (xy 215.9 166.37)
		)
		(stroke
			(width 0)
			(type default)
		)
	)
	(bus
		(pts
			(xy 304.165 121.285) (xy 313.055 121.285)
		)
		(stroke
			(width 0)
			(type default)
		)
	)
	(bus
		(pts
			(xy 133.35 111.76) (xy 169.545 111.76)
		)
		(stroke
			(width 0)
			(type default)
		)
	)
	(bus
		(pts
			(xy 283.21 203.2) (xy 360.045 203.2)
		)
		(stroke
			(width 0)
			(type default)
		)
	)
	(bus
		(pts
			(xy 133.35 77.47) (xy 181.61 77.47)
		)
		(stroke
			(width 0)
			(type default)
		)
	)
	(wire
		(pts
			(xy 26.67 252.73) (xy 26.67 242.57)
		)
		(stroke
			(width 0)
			(type default)
		)
	)
	(bus
		(pts
			(xy 172.72 88.9) (xy 151.13 88.9)
		)
		(stroke
			(width 0)
			(type default)
		)
	)
	(bus
		(pts
			(xy 38.1 46.99) (xy 25.4 46.99)
		)
		(stroke
			(width 0)
			(type default)
		)
	)
	(bus
		(pts
			(xy 133.35 172.72) (xy 181.61 172.72)
		)
		(stroke
			(width 0)
			(type default)
		)
	)
	(wire
		(pts
			(xy 26.67 252.73) (xy 26.67 255.27)
		)
		(stroke
			(width 0)
			(type default)
		)
	)
	(bus
		(pts
			(xy 169.545 123.19) (xy 215.9 123.19)
		)
		(stroke
			(width 0)
			(type default)
		)
	)
	(bus
		(pts
			(xy 304.165 117.475) (xy 333.375 117.475)
		)
		(stroke
			(width 0)
			(type default)
		)
	)
	(bus
		(pts
			(xy 137.16 144.145) (xy 137.16 139.065)
		)
		(stroke
			(width 0)
			(type default)
		)
	)
	(wire
		(pts
			(xy 48.26 199.39) (xy 53.34 199.39)
		)
		(stroke
			(width 0)
			(type default)
		)
	)
	(wire
		(pts
			(xy 69.85 46.99) (xy 101.6 46.99)
		)
		(stroke
			(width 0)
			(type default)
		)
	)
	(bus
		(pts
			(xy 133.35 187.96) (xy 171.45 187.96)
		)
		(stroke
			(width 0)
			(type default)
		)
	)
	(bus
		(pts
			(xy 133.35 123.19) (xy 154.94 123.19)
		)
		(stroke
			(width 0)
			(type default)
		)
	)
	(bus
		(pts
			(xy 38.1 49.53) (xy 31.75 49.53)
		)
		(stroke
			(width 0)
			(type default)
		)
	)
	(bus
		(pts
			(xy 283.21 123.825) (xy 292.735 123.825)
		)
		(stroke
			(width 0)
			(type default)
		)
	)
	(bus
		(pts
			(xy 151.13 84.455) (xy 151.13 88.9)
		)
		(stroke
			(width 0)
			(type default)
		)
	)
	(bus
		(pts
			(xy 133.35 35.56) (xy 154.94 35.56)
		)
		(stroke
			(width 0)
			(type default)
		)
	)
	(bus
		(pts
			(xy 151.13 64.77) (xy 151.13 67.31)
		)
		(stroke
			(width 0)
			(type default)
		)
	)
	(bus
		(pts
			(xy 133.35 175.26) (xy 181.61 175.26)
		)
		(stroke
			(width 0)
			(type default)
		)
	)
	(bus
		(pts
			(xy 283.21 174.625) (xy 316.23 174.625)
		)
		(stroke
			(width 0)
			(type default)
		)
	)
	(wire
		(pts
			(xy 53.34 199.39) (xy 53.34 201.93)
		)
		(stroke
			(width 0)
			(type default)
		)
	)
	(bus
		(pts
			(xy 289.56 186.055) (xy 308.61 186.055)
		)
		(stroke
			(width 0)
			(type default)
		)
	)
	(bus
		(pts
			(xy 304.165 111.125) (xy 304.165 108.585)
		)
		(stroke
			(width 0)
			(type default)
		)
	)
	(bus
		(pts
			(xy 289.56 186.055) (xy 289.56 193.04)
		)
		(stroke
			(width 0)
			(type default)
		)
	)
	(wire
		(pts
			(xy 26.67 242.57) (xy 29.21 242.57)
		)
		(stroke
			(width 0)
			(type default)
		)
	)
	(bus
		(pts
			(xy 175.26 64.77) (xy 175.26 40.64)
		)
		(stroke
			(width 0)
			(type default)
		)
	)
	(bus
		(pts
			(xy 137.16 139.065) (xy 177.8 139.065)
		)
		(stroke
			(width 0)
			(type default)
		)
	)
	(bus
		(pts
			(xy 133.35 130.175) (xy 160.02 130.175)
		)
		(stroke
			(width 0)
			(type default)
		)
	)
	(bus
		(pts
			(xy 304.165 108.585) (xy 325.755 108.585)
		)
		(stroke
			(width 0)
			(type default)
		)
	)
	(bus
		(pts
			(xy 133.35 73.66) (xy 181.61 73.66)
		)
		(stroke
			(width 0)
			(type default)
		)
	)
	(wire
		(pts
			(xy 48.26 184.15) (xy 53.34 184.15)
		)
		(stroke
			(width 0)
			(type default)
		)
	)
	(bus
		(pts
			(xy 137.16 139.065) (xy 137.16 133.985)
		)
		(stroke
			(width 0)
			(type default)
		)
	)
	(bus
		(pts
			(xy 283.21 162.56) (xy 292.735 162.56)
		)
		(stroke
			(width 0)
			(type default)
		)
	)
	(wire
		(pts
			(xy 133.35 81.28) (xy 181.61 81.28)
		)
		(stroke
			(width 0)
			(type default)
		)
	)
	(bus
		(pts
			(xy 289.56 186.055) (xy 289.56 179.07)
		)
		(stroke
			(width 0)
			(type default)
		)
	)
	(bus
		(pts
			(xy 181.61 71.12) (xy 133.35 71.12)
		)
		(stroke
			(width 0)
			(type default)
		)
	)
	(bus
		(pts
			(xy 283.21 117.475) (xy 304.165 117.475)
		)
		(stroke
			(width 0)
			(type default)
		)
	)
	(bus
		(pts
			(xy 133.35 144.145) (xy 137.16 144.145)
		)
		(stroke
			(width 0)
			(type default)
		)
	)
	(bus
		(pts
			(xy 19.05 44.45) (xy 38.1 44.45)
		)
		(stroke
			(width 0)
			(type default)
		)
	)
	(wire
		(pts
			(xy 26.67 252.73) (xy 29.21 252.73)
		)
		(stroke
			(width 0)
			(type default)
		)
	)
	(bus
		(pts
			(xy 304.165 117.475) (xy 304.165 121.285)
		)
		(stroke
			(width 0)
			(type default)
		)
	)
	(bus
		(pts
			(xy 151.13 67.31) (xy 181.61 67.31)
		)
		(stroke
			(width 0)
			(type default)
		)
	)
	(bus
		(pts
			(xy 294.64 227.965) (xy 316.23 227.965)
		)
		(stroke
			(width 0)
			(type default)
		)
	)
	(bus
		(pts
			(xy 133.35 84.455) (xy 151.13 84.455)
		)
		(stroke
			(width 0)
			(type default)
		)
	)
	(bus
		(pts
			(xy 283.21 170.18) (xy 307.34 170.18)
		)
		(stroke
			(width 0)
			(type default)
		)
	)
	(bus
		(pts
			(xy 289.56 186.055) (xy 247.65 186.055)
		)
		(stroke
			(width 0)
			(type default)
		)
	)
	(bus
		(pts
			(xy 133.35 146.685) (xy 181.61 146.685)
		)
		(stroke
			(width 0)
			(type default)
		)
	)
	(bus
		(pts
			(xy 25.4 187.96) (xy 101.6 187.96)
		)
		(stroke
			(width 0)
			(type default)
		)
	)
	(bus
		(pts
			(xy 133.35 198.12) (xy 215.9 198.12)
		)
		(stroke
			(width 0)
			(type default)
		)
	)
	(bus
		(pts
			(xy 133.35 99.06) (xy 181.61 99.06)
		)
		(stroke
			(width 0)
			(type default)
		)
	)
	(bus
		(pts
			(xy 247.65 155.575) (xy 360.045 155.575)
		)
		(stroke
			(width 0)
			(type default)
		)
	)
	(bus
		(pts
			(xy 101.6 105.41) (xy 31.75 105.41)
		)
		(stroke
			(width 0)
			(type default)
		)
	)
	(bus
		(pts
			(xy 69.85 34.29) (xy 91.44 34.29)
		)
		(stroke
			(width 0)
			(type default)
		)
	)
	(bus
		(pts
			(xy 133.35 40.64) (xy 175.26 40.64)
		)
		(stroke
			(width 0)
			(type default)
		)
	)
	(bus
		(pts
			(xy 169.545 111.76) (xy 169.545 123.19)
		)
		(stroke
			(width 0)
			(type default)
		)
	)
	(bus
		(pts
			(xy 177.8 117.475) (xy 177.8 139.065)
		)
		(stroke
			(width 0)
			(type default)
		)
	)
	(wire
		(pts
			(xy 283.21 224.155) (xy 316.23 224.155)
		)
		(stroke
			(width 0)
			(type default)
		)
	)
	(bus
		(pts
			(xy 133.35 127) (xy 154.94 127)
		)
		(stroke
			(width 0)
			(type default)
		)
	)
	(bus
		(pts
			(xy 101.6 191.77) (xy 19.05 191.77)
		)
		(stroke
			(width 0)
			(type default)
		)
	)
	(bus
		(pts
			(xy 69.85 36.83) (xy 91.44 36.83)
		)
		(stroke
			(width 0)
			(type default)
		)
	)
	(bus
		(pts
			(xy 133.35 133.985) (xy 137.16 133.985)
		)
		(stroke
			(width 0)
			(type default)
		)
	)
	(bus
		(pts
			(xy 283.21 200.66) (xy 360.045 200.66)
		)
		(stroke
			(width 0)
			(type default)
		)
	)
	(wire
		(pts
			(xy 26.67 232.41) (xy 26.67 222.25)
		)
		(stroke
			(width 0)
			(type default)
		)
	)
	(bus
		(pts
			(xy 177.8 117.475) (xy 251.46 117.475)
		)
		(stroke
			(width 0)
			(type default)
		)
	)
	(wire
		(pts
			(xy 26.67 242.57) (xy 26.67 232.41)
		)
		(stroke
			(width 0)
			(type default)
		)
	)
	(bus
		(pts
			(xy 181.61 109.22) (xy 160.02 109.22)
		)
		(stroke
			(width 0)
			(type default)
		)
	)
	(bus
		(pts
			(xy 25.4 46.99) (xy 25.4 187.96)
		)
		(stroke
			(width 0)
			(type default)
		)
	)
	(bus
		(pts
			(xy 289.56 193.04) (xy 283.21 193.04)
		)
		(stroke
			(width 0)
			(type default)
		)
	)
	(bus
		(pts
			(xy 283.21 166.37) (xy 307.34 166.37)
		)
		(stroke
			(width 0)
			(type default)
		)
	)
	(bus
		(pts
			(xy 181.61 149.86) (xy 171.45 149.86)
		)
		(stroke
			(width 0)
			(type default)
		)
	)
	(bus
		(pts
			(xy 133.35 67.31) (xy 151.13 67.31)
		)
		(stroke
			(width 0)
			(type default)
		)
	)
	(bus
		(pts
			(xy 31.75 49.53) (xy 31.75 105.41)
		)
		(stroke
			(width 0)
			(type default)
		)
	)
	(bus
		(pts
			(xy 302.26 221.615) (xy 316.23 221.615)
		)
		(stroke
			(width 0)
			(type default)
		)
	)
	(label "USB_SPI{SPI}"
		(at 307.34 166.37 180)
		(effects
			(font
				(size 1.27 1.27)
			)
			(justify right bottom)
		)
	)
	(label "I2C{I2C}"
		(at 302.26 215.265 0)
		(effects
			(font
				(size 1.27 1.27)
			)
			(justify left bottom)
		)
	)
	(label "PLL{PLL-CLK}"
		(at 302.26 221.615 0)
		(effects
			(font
				(size 1.27 1.27)
			)
			(justify left bottom)
		)
	)
	(label "USER_IO{USER-IO}"
		(at 172.72 88.9 180)
		(effects
			(font
				(size 1.27 1.27)
			)
			(justify right bottom)
		)
	)
	(label "SUP_MCU{SUP-MCU}"
		(at 307.34 170.18 180)
		(effects
			(font
				(size 1.27 1.27)
			)
			(justify right bottom)
		)
	)
	(label "SUP_MCU{SUP-MCU}"
		(at 325.755 108.585 180)
		(effects
			(font
				(size 1.27 1.27)
			)
			(justify right bottom)
		)
	)
	(label "I2C{I2C}"
		(at 91.44 34.29 180)
		(effects
			(font
				(size 1.27 1.27)
			)
			(justify right bottom)
		)
	)
	(label "I2C{I2C}"
		(at 154.94 123.19 180)
		(effects
			(font
				(size 1.27 1.27)
			)
			(justify right bottom)
		)
	)
	(label "SUP_MCU{SUP-MCU}"
		(at 172.72 64.77 180)
		(effects
			(font
				(size 1.27 1.27)
			)
			(justify right bottom)
		)
	)
	(label "USB_SPI{SPI}"
		(at 154.94 127 180)
		(effects
			(font
				(size 1.27 1.27)
			)
			(justify right bottom)
		)
	)
	(label "I2C{I2C}"
		(at 154.94 35.56 180)
		(effects
			(font
				(size 1.27 1.27)
			)
			(justify right bottom)
		)
	)
	(label "USER_IO{USER-IO}"
		(at 308.61 186.055 180)
		(effects
			(font
				(size 1.27 1.27)
			)
			(justify right bottom)
		)
	)
	(label "SUP_MCU{SUP-MCU}"
		(at 154.94 38.1 180)
		(effects
			(font
				(size 1.27 1.27)
			)
			(justify right bottom)
		)
	)
	(label "SUP_MCU{SUP-MCU}"
		(at 91.44 36.83 180)
		(effects
			(font
				(size 1.27 1.27)
			)
			(justify right bottom)
		)
	)
	(label "I2C{I2C}"
		(at 313.055 121.285 180)
		(effects
			(font
				(size 1.27 1.27)
			)
			(justify right bottom)
		)
	)
	(label "PLL{PLL-CLK}"
		(at 162.56 105.41 0)
		(effects
			(font
				(size 1.27 1.27)
			)
			(justify left bottom)
		)
	)
	(label "SUP_MCU{SUP-MCU}"
		(at 294.64 227.965 0)
		(effects
			(font
				(size 1.27 1.27)
			)
			(justify left bottom)
		)
	)
	(symbol
		(lib_id "antmicroTestPoints:TP_1206_SMD_RCW-0C")
		(at 48.26 199.39 180)
		(unit 1)
		(exclude_from_sim no)
		(in_bom yes)
		(on_board yes)
		(dnp no)
		(fields_autoplaced yes)
		(property "Reference" "TP9"
			(at 45.212 193.675 0)
			(effects
				(font
					(size 1.27 1.27)
				)
			)
		)
		(property "Value" "TP_1206_SMD_RCW-0C"
			(at 45.212 196.215 0)
			(effects
				(font
					(size 1.27 1.27)
					(thickness 0.15)
				)
			)
		)
		(property "Footprint" "antmicro-footprints:TP_1206_SMD_RCW-0C"
			(at 30.48 189.23 0)
			(effects
				(font
					(size 1.27 1.27)
					(thickness 0.15)
				)
				(justify left bottom)
				(hide yes)
			)
		)
		(property "Datasheet" "https://www.te.com/commerce/DocumentDelivery/DDEController?Action=srchrtrv&DocNm=1773266&DocType=DS&DocLang=English"
			(at 30.48 186.69 0)
			(effects
				(font
					(size 1.27 1.27)
					(thickness 0.15)
				)
				(justify left bottom)
				(hide yes)
			)
		)
		(property "Description" ""
			(at 48.26 199.39 0)
			(effects
				(font
					(size 1.27 1.27)
				)
			)
		)
		(property "MPN" "RCW-0C"
			(at 30.48 184.15 0)
			(effects
				(font
					(size 1.27 1.27)
					(thickness 0.15)
				)
				(justify left bottom)
				(hide yes)
			)
		)
		(property "Manufacturer" "TE Connectivity"
			(at 30.48 181.61 0)
			(effects
				(font
					(size 1.27 1.27)
					(thickness 0.15)
				)
				(justify left bottom)
				(hide yes)
			)
		)
		(property "Author" "Antmicro"
			(at 30.48 179.07 0)
			(effects
				(font
					(size 1.27 1.27)
					(thickness 0.15)
				)
				(justify left bottom)
				(hide yes)
			)
		)
		(property "License" "Apache-2.0"
			(at 30.48 176.53 0)
			(effects
				(font
					(size 1.27 1.27)
					(thickness 0.15)
				)
				(justify left bottom)
				(hide yes)
			)
		)
		(pin "1"
		)
		(instances
			(project "k410t-devboard"
				(path ""
					(reference "TP9")
					(unit 1)
				)
			)
		)
	)
	(symbol
		(lib_id "antmicroTestPoints:TP_1206_SMD_RCW-0C")
		(at 48.26 184.15 180)
		(unit 1)
		(exclude_from_sim no)
		(in_bom yes)
		(on_board yes)
		(dnp no)
		(fields_autoplaced yes)
		(property "Reference" "TP10"
			(at 45.212 178.435 0)
			(effects
				(font
					(size 1.27 1.27)
				)
			)
		)
		(property "Value" "TP_1206_SMD_RCW-0C"
			(at 45.212 180.975 0)
			(effects
				(font
					(size 1.27 1.27)
					(thickness 0.15)
				)
			)
		)
		(property "Footprint" "antmicro-footprints:TP_1206_SMD_RCW-0C"
			(at 30.48 173.99 0)
			(effects
				(font
					(size 1.27 1.27)
					(thickness 0.15)
				)
				(justify left bottom)
				(hide yes)
			)
		)
		(property "Datasheet" "https://www.te.com/commerce/DocumentDelivery/DDEController?Action=srchrtrv&DocNm=1773266&DocType=DS&DocLang=English"
			(at 30.48 171.45 0)
			(effects
				(font
					(size 1.27 1.27)
					(thickness 0.15)
				)
				(justify left bottom)
				(hide yes)
			)
		)
		(property "Description" ""
			(at 48.26 184.15 0)
			(effects
				(font
					(size 1.27 1.27)
				)
			)
		)
		(property "MPN" "RCW-0C"
			(at 30.48 168.91 0)
			(effects
				(font
					(size 1.27 1.27)
					(thickness 0.15)
				)
				(justify left bottom)
				(hide yes)
			)
		)
		(property "Manufacturer" "TE Connectivity"
			(at 30.48 166.37 0)
			(effects
				(font
					(size 1.27 1.27)
					(thickness 0.15)
				)
				(justify left bottom)
				(hide yes)
			)
		)
		(property "Author" "Antmicro"
			(at 30.48 163.83 0)
			(effects
				(font
					(size 1.27 1.27)
					(thickness 0.15)
				)
				(justify left bottom)
				(hide yes)
			)
		)
		(property "License" "Apache-2.0"
			(at 30.48 161.29 0)
			(effects
				(font
					(size 1.27 1.27)
					(thickness 0.15)
				)
				(justify left bottom)
				(hide yes)
			)
		)
		(pin "1"
		)
		(instances
			(project "k410t-devboard"
				(path ""
					(reference "TP10")
					(unit 1)
				)
			)
		)
	)
	(symbol
		(lib_id "antmicroMechanicalParts:MP_Pad6mm_Drill3mm")
		(at 29.21 252.73 0)
		(unit 1)
		(exclude_from_sim no)
		(in_bom no)
		(on_board yes)
		(dnp no)
		(fields_autoplaced yes)
		(property "Reference" "MH4"
			(at 38.1 251.46 0)
			(effects
				(font
					(size 1.27 1.27)
					(thickness 0.15)
				)
				(justify left)
			)
		)
		(property "Value" "MP_Pad6mm_Drill3mm"
			(at 38.1 254 0)
			(effects
				(font
					(size 1.27 1.27)
					(thickness 0.15)
				)
				(justify left)
			)
		)
		(property "Footprint" "antmicro-footprints:MP_Pad6mm_Drill3mm"
			(at 49.53 260.35 0)
			(effects
				(font
					(size 1.27 1.27)
					(thickness 0.15)
				)
				(justify left bottom)
				(hide yes)
			)
		)
		(property "Datasheet" ""
			(at 46.05 268.3 0)
			(effects
				(font
					(size 1.27 1.27)
					(thickness 0.15)
				)
				(justify left bottom)
				(hide yes)
			)
		)
		(property "Description" ""
			(at 29.21 252.73 0)
			(effects
				(font
					(size 1.27 1.27)
				)
			)
		)
		(property "MPN" ""
			(at 29.21 252.73 0)
			(effects
				(font
					(size 1.27 1.27)
				)
				(hide yes)
			)
		)
		(property "Manufacturer" ""
			(at 29.21 252.73 0)
			(effects
				(font
					(size 1.27 1.27)
				)
				(hide yes)
			)
		)
		(property "Author" "Antmicro"
			(at 49.53 262.89 0)
			(effects
				(font
					(size 1.27 1.27)
					(thickness 0.15)
				)
				(justify left bottom)
				(hide yes)
			)
		)
		(property "License" "Apache-2.0"
			(at 49.53 265.43 0)
			(effects
				(font
					(size 1.27 1.27)
					(thickness 0.15)
				)
				(justify left bottom)
				(hide yes)
			)
		)
		(pin "1"
		)
		(instances
			(project "k410t-devboard"
				(path ""
					(reference "MH4")
					(unit 1)
				)
			)
		)
	)
	(symbol
		(lib_id "antmicroMechanicalParts:MP_Pad6mm_Drill3mm")
		(at 29.21 232.41 0)
		(unit 1)
		(exclude_from_sim no)
		(in_bom no)
		(on_board yes)
		(dnp no)
		(fields_autoplaced yes)
		(property "Reference" "MH2"
			(at 38.1 231.14 0)
			(effects
				(font
					(size 1.27 1.27)
					(thickness 0.15)
				)
				(justify left)
			)
		)
		(property "Value" "MP_Pad6mm_Drill3mm"
			(at 38.1 233.68 0)
			(effects
				(font
					(size 1.27 1.27)
					(thickness 0.15)
				)
				(justify left)
			)
		)
		(property "Footprint" "antmicro-footprints:MP_Pad6mm_Drill3mm"
			(at 49.53 240.03 0)
			(effects
				(font
					(size 1.27 1.27)
					(thickness 0.15)
				)
				(justify left bottom)
				(hide yes)
			)
		)
		(property "Datasheet" ""
			(at 46.05 247.98 0)
			(effects
				(font
					(size 1.27 1.27)
					(thickness 0.15)
				)
				(justify left bottom)
				(hide yes)
			)
		)
		(property "Description" ""
			(at 29.21 232.41 0)
			(effects
				(font
					(size 1.27 1.27)
				)
			)
		)
		(property "MPN" ""
			(at 29.21 232.41 0)
			(effects
				(font
					(size 1.27 1.27)
				)
				(hide yes)
			)
		)
		(property "Manufacturer" ""
			(at 29.21 232.41 0)
			(effects
				(font
					(size 1.27 1.27)
				)
				(hide yes)
			)
		)
		(property "Author" "Antmicro"
			(at 49.53 242.57 0)
			(effects
				(font
					(size 1.27 1.27)
					(thickness 0.15)
				)
				(justify left bottom)
				(hide yes)
			)
		)
		(property "License" "Apache-2.0"
			(at 49.53 245.11 0)
			(effects
				(font
					(size 1.27 1.27)
					(thickness 0.15)
				)
				(justify left bottom)
				(hide yes)
			)
		)
		(pin "1"
		)
		(instances
			(project "k410t-devboard"
				(path ""
					(reference "MH2")
					(unit 1)
				)
			)
		)
	)
	(symbol
		(lib_id "antmicropower:GND")
		(at 53.34 201.93 0)
		(unit 1)
		(exclude_from_sim no)
		(in_bom yes)
		(on_board yes)
		(dnp no)
		(property "Reference" "#PWR07"
			(at 53.34 208.28 0)
			(effects
				(font
					(size 1.27 1.27)
				)
				(hide yes)
			)
		)
		(property "Value" "GND"
			(at 53.34 205.74 0)
			(effects
				(font
					(size 1.27 1.27)
				)
			)
		)
		(property "Footprint" ""
			(at 62.23 209.55 0)
			(effects
				(font
					(size 1.27 1.27)
					(thickness 0.15)
				)
				(justify left bottom)
				(hide yes)
			)
		)
		(property "Datasheet" ""
			(at 62.23 214.63 0)
			(effects
				(font
					(size 1.27 1.27)
					(thickness 0.15)
				)
				(justify left bottom)
				(hide yes)
			)
		)
		(property "Description" ""
			(at 53.34 201.93 0)
			(effects
				(font
					(size 1.27 1.27)
				)
			)
		)
		(property "Author" "Antmicro"
			(at 62.23 209.55 0)
			(effects
				(font
					(size 1.27 1.27)
					(thickness 0.15)
				)
				(justify left bottom)
				(hide yes)
			)
		)
		(property "License" "Apache-2.0"
			(at 62.23 212.09 0)
			(effects
				(font
					(size 1.27 1.27)
					(thickness 0.15)
				)
				(justify left bottom)
				(hide yes)
			)
		)
		(pin "1"
		)
		(instances
			(project "k410t-devboard"
				(path ""
					(reference "#PWR07")
					(unit 1)
				)
			)
		)
	)
	(symbol
		(lib_id "antmicroMechanicalParts:MP_Pad6mm_Drill3mm")
		(at 29.21 242.57 0)
		(unit 1)
		(exclude_from_sim no)
		(in_bom no)
		(on_board yes)
		(dnp no)
		(fields_autoplaced yes)
		(property "Reference" "MH3"
			(at 38.1 241.3 0)
			(effects
				(font
					(size 1.27 1.27)
					(thickness 0.15)
				)
				(justify left)
			)
		)
		(property "Value" "MP_Pad6mm_Drill3mm"
			(at 38.1 243.84 0)
			(effects
				(font
					(size 1.27 1.27)
					(thickness 0.15)
				)
				(justify left)
			)
		)
		(property "Footprint" "antmicro-footprints:MP_Pad6mm_Drill3mm"
			(at 49.53 250.19 0)
			(effects
				(font
					(size 1.27 1.27)
					(thickness 0.15)
				)
				(justify left bottom)
				(hide yes)
			)
		)
		(property "Datasheet" ""
			(at 46.05 258.14 0)
			(effects
				(font
					(size 1.27 1.27)
					(thickness 0.15)
				)
				(justify left bottom)
				(hide yes)
			)
		)
		(property "Description" ""
			(at 29.21 242.57 0)
			(effects
				(font
					(size 1.27 1.27)
				)
			)
		)
		(property "MPN" ""
			(at 29.21 242.57 0)
			(effects
				(font
					(size 1.27 1.27)
				)
				(hide yes)
			)
		)
		(property "Manufacturer" ""
			(at 29.21 242.57 0)
			(effects
				(font
					(size 1.27 1.27)
				)
				(hide yes)
			)
		)
		(property "Author" "Antmicro"
			(at 49.53 252.73 0)
			(effects
				(font
					(size 1.27 1.27)
					(thickness 0.15)
				)
				(justify left bottom)
				(hide yes)
			)
		)
		(property "License" "Apache-2.0"
			(at 49.53 255.27 0)
			(effects
				(font
					(size 1.27 1.27)
					(thickness 0.15)
				)
				(justify left bottom)
				(hide yes)
			)
		)
		(pin "1"
		)
		(instances
			(project "k410t-devboard"
				(path ""
					(reference "MH3")
					(unit 1)
				)
			)
		)
	)
	(symbol
		(lib_id "antmicropower:GND")
		(at 53.34 186.69 0)
		(unit 1)
		(exclude_from_sim no)
		(in_bom yes)
		(on_board yes)
		(dnp no)
		(property "Reference" "#PWR02"
			(at 53.34 193.04 0)
			(effects
				(font
					(size 1.27 1.27)
				)
				(hide yes)
			)
		)
		(property "Value" "GND"
			(at 53.34 190.5 0)
			(effects
				(font
					(size 1.27 1.27)
				)
			)
		)
		(property "Footprint" ""
			(at 62.23 194.31 0)
			(effects
				(font
					(size 1.27 1.27)
					(thickness 0.15)
				)
				(justify left bottom)
				(hide yes)
			)
		)
		(property "Datasheet" ""
			(at 62.23 199.39 0)
			(effects
				(font
					(size 1.27 1.27)
					(thickness 0.15)
				)
				(justify left bottom)
				(hide yes)
			)
		)
		(property "Description" ""
			(at 53.34 186.69 0)
			(effects
				(font
					(size 1.27 1.27)
				)
			)
		)
		(property "Author" "Antmicro"
			(at 62.23 194.31 0)
			(effects
				(font
					(size 1.27 1.27)
					(thickness 0.15)
				)
				(justify left bottom)
				(hide yes)
			)
		)
		(property "License" "Apache-2.0"
			(at 62.23 196.85 0)
			(effects
				(font
					(size 1.27 1.27)
					(thickness 0.15)
				)
				(justify left bottom)
				(hide yes)
			)
		)
		(pin "1"
		)
		(instances
			(project "k410t-devboard"
				(path ""
					(reference "#PWR02")
					(unit 1)
				)
			)
		)
	)
	(symbol
		(lib_id "antmicroMechanicalParts:Heatsink_960-31-18-S-AB-0")
		(at 184.785 215.9 0)
		(unit 1)
		(exclude_from_sim no)
		(in_bom no)
		(on_board yes)
		(dnp yes)
		(property "Reference" "HS1"
			(at 188.595 212.7249 0)
			(effects
				(font
					(size 1.27 1.27)
				)
				(justify left)
			)
		)
		(property "Value" "Heatsink_960-31-18-S-AB-0"
			(at 188.595 215.2649 0)
			(effects
				(font
					(size 1.27 1.27)
					(thickness 0.15)
				)
				(justify left)
			)
		)
		(property "Footprint" "antmicro-footprints:Heatsink_960-31-18-S-AB-0"
			(at 202.565 223.52 0)
			(effects
				(font
					(size 1.27 1.27)
					(thickness 0.15)
				)
				(justify left bottom)
				(hide yes)
			)
		)
		(property "Datasheet" "https://media.digikey.com/pdf/Data%20Sheets/Wakefield%20Thermal%20PDFs/960_Series.pdf"
			(at 202.565 226.06 0)
			(effects
				(font
					(size 1.27 1.27)
					(thickness 0.15)
				)
				(justify left bottom)
				(hide yes)
			)
		)
		(property "Description" ""
			(at 184.785 215.9 0)
			(effects
				(font
					(size 1.27 1.27)
				)
			)
		)
		(property "MPN" "960-31-18-S-AB-0"
			(at 202.565 228.6 0)
			(effects
				(font
					(size 1.27 1.27)
					(thickness 0.15)
				)
				(justify left bottom)
				(hide yes)
			)
		)
		(property "Manufacturer" "Wakefield-Vette"
			(at 202.565 231.14 0)
			(effects
				(font
					(size 1.27 1.27)
					(thickness 0.15)
				)
				(justify left bottom)
				(hide yes)
			)
		)
		(property "Author" "Antmicro"
			(at 202.565 233.68 0)
			(effects
				(font
					(size 1.27 1.27)
					(thickness 0.15)
				)
				(justify left bottom)
				(hide yes)
			)
		)
		(property "License" "Apache-2.0"
			(at 202.565 236.22 0)
			(effects
				(font
					(size 1.27 1.27)
					(thickness 0.15)
				)
				(justify left bottom)
				(hide yes)
			)
		)
		(property "DNP" "DNP"
			(at 190.246 217.297 0)
			(effects
				(font
					(size 1 1)
				)
			)
		)
		(instances
			(project "k410t-devboard"
				(path ""
					(reference "HS1")
					(unit 1)
				)
			)
		)
	)
	(symbol
		(lib_id "antmicropower:GND")
		(at 26.67 255.27 0)
		(unit 1)
		(exclude_from_sim no)
		(in_bom yes)
		(on_board yes)
		(dnp no)
		(property "Reference" "#PWR0504"
			(at 26.67 261.62 0)
			(effects
				(font
					(size 1.27 1.27)
				)
				(hide yes)
			)
		)
		(property "Value" "GND"
			(at 26.67 259.08 0)
			(effects
				(font
					(size 1.27 1.27)
				)
			)
		)
		(property "Footprint" ""
			(at 35.56 262.89 0)
			(effects
				(font
					(size 1.27 1.27)
					(thickness 0.15)
				)
				(justify left bottom)
				(hide yes)
			)
		)
		(property "Datasheet" ""
			(at 35.56 267.97 0)
			(effects
				(font
					(size 1.27 1.27)
					(thickness 0.15)
				)
				(justify left bottom)
				(hide yes)
			)
		)
		(property "Description" ""
			(at 26.67 255.27 0)
			(effects
				(font
					(size 1.27 1.27)
				)
			)
		)
		(property "Author" "Antmicro"
			(at 35.56 262.89 0)
			(effects
				(font
					(size 1.27 1.27)
					(thickness 0.15)
				)
				(justify left bottom)
				(hide yes)
			)
		)
		(property "License" "Apache-2.0"
			(at 35.56 265.43 0)
			(effects
				(font
					(size 1.27 1.27)
					(thickness 0.15)
				)
				(justify left bottom)
				(hide yes)
			)
		)
		(pin "1"
		)
		(instances
			(project "k410t-devboard"
				(path ""
					(reference "#PWR0504")
					(unit 1)
				)
			)
		)
	)
	(symbol
		(lib_id "antmicropower:GND")
		(at 29.21 222.25 0)
		(unit 1)
		(exclude_from_sim no)
		(in_bom yes)
		(on_board yes)
		(dnp no)
		(property "Reference" "#MH01"
			(at 41.91 220.9799 0)
			(effects
				(font
					(size 1.27 1.27)
					(thickness 0.15)
				)
				(justify left)
			)
		)
		(property "Value" "GND"
			(at 41.91 223.5199 0)
			(effects
				(font
					(size 1.27 1.27)
					(thickness 0.15)
				)
				(justify left)
			)
		)
		(property "Footprint" ""
			(at 49.53 229.87 0)
			(effects
				(font
					(size 1.27 1.27)
					(thickness 0.15)
				)
				(justify left bottom)
				(hide yes)
			)
		)
		(property "Datasheet" ""
			(at 49.53 232.41 0)
			(effects
				(font
					(size 1.27 1.27)
					(thickness 0.15)
				)
				(justify left bottom)
				(hide yes)
			)
		)
		(property "Description" ""
			(at 29.21 222.25 0)
			(effects
				(font
					(size 1.27 1.27)
				)
			)
		)
		(property "MPN" "RCW-0C"
			(at 29.21 222.25 0)
			(effects
				(font
					(size 1.27 1.27)
				)
				(hide yes)
			)
		)
		(property "Manufacturer" "TE Connectivity"
			(at 29.21 222.25 0)
			(effects
				(font
					(size 1.27 1.27)
				)
				(hide yes)
			)
		)
		(property "Author" "Antmicro"
			(at 49.53 234.95 0)
			(effects
				(font
					(size 1.27 1.27)
					(thickness 0.15)
				)
				(justify left bottom)
				(hide yes)
			)
		)
		(property "License" "Apache-2.0"
			(at 49.53 237.49 0)
			(effects
				(font
					(size 1.27 1.27)
					(thickness 0.15)
				)
				(justify left bottom)
				(hide yes)
			)
		)
		(pin "1"
		)
		(instances
			(project "k410t-devboard"
				(path ""
					(reference "#MH01")
					(unit 1)
				)
			)
		)
	)
	(sheet
		(at 251.46 60.325)
		(size 31.75 19.05)
		(exclude_from_sim no)
		(in_bom yes)
		(on_board yes)
		(dnp no)
		(fields_autoplaced yes)
		(stroke
			(width 0.1524)
			(type solid)
		)
		(fill
			(color 0 0 0 0.0000)
		)
		(property "Sheetname" "FPGA supply"
			(at 251.46 59.6134 0)
			(effects
				(font
					(size 1.27 1.27)
				)
				(justify left bottom)
			)
		)
		(property "Sheetfile" "fpga-supply.kicad_sch"
			(at 251.46 79.9596 0)
			(effects
				(font
					(size 1.27 1.27)
				)
				(justify left top)
			)
		)
		(instances
			(project "k410t-devboard"
				(path ""
					(page "2")
				)
			)
		)
	)
	(sheet
		(at 101.6 140.97)
		(size 31.75 36.83)
		(exclude_from_sim no)
		(in_bom yes)
		(on_board yes)
		(dnp no)
		(fields_autoplaced yes)
		(stroke
			(width 0.1524)
			(type solid)
		)
		(fill
			(color 0 0 0 0.0000)
		)
		(property "Sheetname" "FMC+ HSPC"
			(at 101.6 140.2584 0)
			(effects
				(font
					(size 1.27 1.27)
				)
				(justify left bottom)
			)
		)
		(property "Sheetfile" "fmc-hspc.kicad_sch"
			(at 101.6 178.3846 0)
			(effects
				(font
					(size 1.27 1.27)
				)
				(justify left top)
			)
		)
		(pin "GTX115{MGTX}" bidirectional
			(at 133.35 172.72 0)
			(effects
				(font
					(size 1.27 1.27)
				)
				(justify right)
			)
		)
		(pin "GTX116{MGTX}" bidirectional
			(at 133.35 175.26 0)
			(effects
				(font
					(size 1.27 1.27)
				)
				(justify right)
			)
		)
		(pin "JTAG{JTAG}" bidirectional
			(at 133.35 144.145 0)
			(effects
				(font
					(size 1.27 1.27)
				)
				(justify right)
			)
		)
		(pin "FMC{FMC-IO}" bidirectional
			(at 133.35 146.685 0)
			(effects
				(font
					(size 1.27 1.27)
				)
				(justify right)
			)
		)
		(pin "FMC{FMC-CTRL}" bidirectional
			(at 133.35 166.37 0)
			(effects
				(font
					(size 1.27 1.27)
				)
				(justify right)
			)
		)
		(instances
			(project "k410t-devboard"
				(path ""
					(page "14")
				)
			)
		)
	)
	(sheet
		(at 101.6 95.25)
		(size 31.75 40.64)
		(exclude_from_sim no)
		(in_bom yes)
		(on_board yes)
		(dnp no)
		(fields_autoplaced yes)
		(stroke
			(width 0.1524)
			(type solid)
		)
		(fill
			(color 0 0 0 0.0000)
		)
		(property "Sheetname" "USB PHY"
			(at 101.6 94.5384 0)
			(effects
				(font
					(size 1.27 1.27)
				)
				(justify left bottom)
			)
		)
		(property "Sheetfile" "usb-phy.kicad_sch"
			(at 101.6 136.4746 0)
			(effects
				(font
					(size 1.27 1.27)
				)
				(justify left top)
			)
		)
		(pin "USB_HOST{SPI-USB}" bidirectional
			(at 133.35 111.76 0)
			(effects
				(font
					(size 1.27 1.27)
				)
				(justify right)
			)
		)
		(pin "USB_USER{USB-FPGA-PHY}" bidirectional
			(at 133.35 130.175 0)
			(effects
				(font
					(size 1.27 1.27)
				)
				(justify right)
			)
		)
		(pin "USB_DBG_PD{USB-C-PD}" bidirectional
			(at 101.6 105.41 180)
			(effects
				(font
					(size 1.27 1.27)
				)
				(justify left)
			)
		)
		(pin "JTAG{JTAG}" bidirectional
			(at 133.35 133.985 0)
			(effects
				(font
					(size 1.27 1.27)
				)
				(justify right)
			)
		)
		(pin "UART1{UART}" bidirectional
			(at 133.35 101.6 0)
			(effects
				(font
					(size 1.27 1.27)
				)
				(justify right)
			)
		)
		(pin "UART0{UART}" bidirectional
			(at 133.35 99.06 0)
			(effects
				(font
					(size 1.27 1.27)
				)
				(justify right)
			)
		)
		(pin "FTDI_SPI{SPI}" bidirectional
			(at 133.35 127 0)
			(effects
				(font
					(size 1.27 1.27)
				)
				(justify right)
			)
		)
		(pin "I2C{I2C}" bidirectional
			(at 133.35 123.19 0)
			(effects
				(font
					(size 1.27 1.27)
				)
				(justify right)
			)
		)
		(instances
			(project "k410t-devboard"
				(path ""
					(page "12")
				)
			)
		)
	)
	(sheet
		(at 251.46 160.02)
		(size 31.75 21.59)
		(exclude_from_sim no)
		(in_bom yes)
		(on_board yes)
		(dnp no)
		(fields_autoplaced yes)
		(stroke
			(width 0.1524)
			(type solid)
		)
		(fill
			(color 0 0 0 0.0000)
		)
		(property "Sheetname" "FPGA Bank 14 & 15"
			(at 251.46 159.3084 0)
			(effects
				(font
					(size 1.27 1.27)
				)
				(justify left bottom)
			)
		)
		(property "Sheetfile" "fpga-bank-14-15.kicad_sch"
			(at 251.46 182.1946 0)
			(effects
				(font
					(size 1.27 1.27)
				)
				(justify left top)
			)
		)
		(pin "SRAM{SRAM}" input
			(at 283.21 174.625 0)
			(effects
				(font
					(size 1.27 1.27)
				)
				(justify right)
			)
		)
		(pin "SYSTEM_FLASH{SPI-FLASH}" bidirectional
			(at 283.21 162.56 0)
			(effects
				(font
					(size 1.27 1.27)
				)
				(justify right)
			)
		)
		(pin "USB_SPI{SPI}" bidirectional
			(at 283.21 166.37 0)
			(effects
				(font
					(size 1.27 1.27)
				)
				(justify right)
			)
		)
		(pin "SUP_MCU{SUP-MCU}" bidirectional
			(at 283.21 170.18 0)
			(effects
				(font
					(size 1.27 1.27)
				)
				(justify right)
			)
		)
		(pin "USER_IO{USER-IO}" bidirectional
			(at 283.21 179.07 0)
			(effects
				(font
					(size 1.27 1.27)
				)
				(justify right)
			)
		)
		(instances
			(project "k410t-devboard"
				(path ""
					(page "18")
				)
			)
		)
	)
	(sheet
		(at 251.46 190.5)
		(size 31.75 37.465)
		(exclude_from_sim no)
		(in_bom yes)
		(on_board yes)
		(dnp no)
		(stroke
			(width 0.1524)
			(type solid)
		)
		(fill
			(color 0 0 0 0.0000)
		)
		(property "Sheetname" "FPGA Bank 33 & 34"
			(at 251.46 189.7884 0)
			(effects
				(font
					(size 1.27 1.27)
				)
				(justify left bottom)
			)
		)
		(property "Sheetfile" "fpga-bank-33-34.kicad_sch"
			(at 250.19 229.235 0)
			(effects
				(font
					(size 1.27 1.27)
				)
				(justify left top)
			)
		)
		(pin "USER_IO{USER-IO}" bidirectional
			(at 283.21 193.04 0)
			(effects
				(font
					(size 1.27 1.27)
				)
				(justify right)
			)
		)
		(pin "SD_CARD{SD-CARD}" bidirectional
			(at 283.21 203.2 0)
			(effects
				(font
					(size 1.27 1.27)
				)
				(justify right)
			)
		)
		(pin "USR_FLASH_0{SPI-FLASH}" bidirectional
			(at 283.21 200.66 0)
			(effects
				(font
					(size 1.27 1.27)
				)
				(justify right)
			)
		)
		(pin "SYS{CLK}" input
			(at 283.21 217.805 0)
			(effects
				(font
					(size 1.27 1.27)
				)
				(justify right)
			)
		)
		(pin "LVDS_XO_200M_ENA" output
			(at 283.21 224.155 0)
			(effects
				(font
					(size 1.27 1.27)
				)
				(justify right)
			)
		)
		(pin "DDR{DDR3_DRAM}" input
			(at 283.21 195.58 0)
			(effects
				(font
					(size 1.27 1.27)
				)
				(justify right)
			)
		)
		(instances
			(project "k410t-devboard"
				(path ""
					(page "24")
				)
			)
		)
	)
	(sheet
		(at 251.46 107.315)
		(size 31.75 19.05)
		(exclude_from_sim no)
		(in_bom yes)
		(on_board yes)
		(dnp no)
		(stroke
			(width 0.1524)
			(type solid)
		)
		(fill
			(color 0 0 0 0.0000)
		)
		(property "Sheetname" "FPGA Config"
			(at 251.46 106.6034 0)
			(effects
				(font
					(size 1.27 1.27)
				)
				(justify left bottom)
			)
		)
		(property "Sheetfile" "fpga-config.kicad_sch"
			(at 251.46 126.365 0)
			(effects
				(font
					(size 1.27 1.27)
				)
				(justify left top)
			)
		)
		(pin "SYSTEM_FLASH{SPI-FLASH}" bidirectional
			(at 283.21 123.825 0)
			(effects
				(font
					(size 1.27 1.27)
				)
				(justify right)
			)
		)
		(pin "JTAG{JTAG}" bidirectional
			(at 251.46 117.475 180)
			(effects
				(font
					(size 1.27 1.27)
				)
				(justify left)
			)
		)
		(pin "SUP_MCU{SUP-MCU}" bidirectional
			(at 283.21 111.125 0)
			(effects
				(font
					(size 1.27 1.27)
				)
				(justify right)
			)
		)
		(pin "I2C{I2C}" bidirectional
			(at 283.21 117.475 0)
			(effects
				(font
					(size 1.27 1.27)
				)
				(justify right)
			)
		)
		(instances
			(project "k410t-devboard"
				(path ""
					(page "3")
				)
			)
		)
	)
	(sheet
		(at 360.045 153.035)
		(size 31.75 52.705)
		(exclude_from_sim no)
		(in_bom yes)
		(on_board yes)
		(dnp no)
		(stroke
			(width 0.1524)
			(type solid)
		)
		(fill
			(color 0 0 0 0.0000)
		)
		(property "Sheetname" "SPI Flash + SD Card"
			(at 360.045 151.765 0)
			(effects
				(font
					(size 1.27 1.27)
				)
				(justify left bottom)
			)
		)
		(property "Sheetfile" "spi-flash.kicad_sch"
			(at 360.045 207.01 0)
			(effects
				(font
					(size 1.27 1.27)
				)
				(justify left top)
			)
		)
		(pin "USR_FLASH_0{SPI-FLASH}" bidirectional
			(at 360.045 200.66 180)
			(effects
				(font
					(size 1.27 1.27)
				)
				(justify left)
			)
		)
		(pin "SYSTEM_FLASH{SPI-FLASH}" bidirectional
			(at 360.045 162.56 180)
			(effects
				(font
					(size 1.27 1.27)
				)
				(justify left)
			)
		)
		(pin "SD_CARD{SD-CARD}" bidirectional
			(at 360.045 203.2 180)
			(effects
				(font
					(size 1.27 1.27)
				)
				(justify left)
			)
		)
		(pin "USR_FLASH_1{SPI-FLASH}" bidirectional
			(at 360.045 155.575 180)
			(effects
				(font
					(size 1.27 1.27)
				)
				(justify left)
			)
		)
		(instances
			(project "k410t-devboard"
				(path ""
					(page "10")
				)
			)
		)
	)
	(sheet
		(at 181.61 59.69)
		(size 31.75 54.61)
		(exclude_from_sim no)
		(in_bom yes)
		(on_board yes)
		(dnp no)
		(stroke
			(width 0.1524)
			(type solid)
		)
		(fill
			(color 0 0 0 0.0000)
		)
		(property "Sheetname" "FPGA Bank 12 & 13"
			(at 181.61 58.9784 0)
			(effects
				(font
					(size 1.27 1.27)
				)
				(justify left bottom)
			)
		)
		(property "Sheetfile" "fpga-bank-12-13.kicad_sch"
			(at 181.61 114.935 0)
			(effects
				(font
					(size 1.27 1.27)
				)
				(justify left top)
			)
		)
		(pin "UART0{UART}" input
			(at 181.61 99.06 180)
			(effects
				(font
					(size 1.27 1.27)
				)
				(justify left)
			)
		)
		(pin "UART1{UART}" input
			(at 181.61 101.6 180)
			(effects
				(font
					(size 1.27 1.27)
				)
				(justify left)
			)
		)
		(pin "CW_HEADER{CW-20PIN}" bidirectional
			(at 181.61 77.47 180)
			(effects
				(font
					(size 1.27 1.27)
				)
				(justify left)
			)
		)
		(pin "SUP_MCU{SUP-MCU}" bidirectional
			(at 181.61 67.31 180)
			(effects
				(font
					(size 1.27 1.27)
				)
				(justify left)
			)
		)
		(pin "FAN_PWM_CTRL" output
			(at 181.61 81.28 180)
			(effects
				(font
					(size 1.27 1.27)
				)
				(justify left)
			)
		)
		(pin "PMOD_B{PMOD}" bidirectional
			(at 181.61 73.66 180)
			(effects
				(font
					(size 1.27 1.27)
				)
				(justify left)
			)
		)
		(pin "USB_USER{USB-FPGA-PHY}" bidirectional
			(at 181.61 109.22 180)
			(effects
				(font
					(size 1.27 1.27)
				)
				(justify left)
			)
		)
		(pin "USB_HOST{SPI-USB}" bidirectional
			(at 181.61 111.76 180)
			(effects
				(font
					(size 1.27 1.27)
				)
				(justify left)
			)
		)
		(pin "USER_IO{USER-IO}" bidirectional
			(at 181.61 84.455 180)
			(effects
				(font
					(size 1.27 1.27)
				)
				(justify left)
			)
		)
		(pin "PB_CTRL{PB-CTRL}" bidirectional
			(at 181.61 64.77 180)
			(effects
				(font
					(size 1.27 1.27)
				)
				(justify left)
			)
		)
		(pin "PLL{PLL-CLK}" output
			(at 181.61 105.41 180)
			(effects
				(font
					(size 1.27 1.27)
				)
				(justify left)
			)
		)
		(pin "PMOD_A{PMOD}" bidirectional
			(at 181.61 71.12 180)
			(effects
				(font
					(size 1.27 1.27)
				)
				(justify left)
			)
		)
		(instances
			(project "k410t-devboard"
				(path ""
					(page "26")
				)
			)
		)
	)
	(sheet
		(at 215.9 120.65)
		(size 31.75 82.55)
		(exclude_from_sim no)
		(in_bom yes)
		(on_board yes)
		(dnp no)
		(stroke
			(width 0.1524)
			(type solid)
		)
		(fill
			(color 0 0 0 0.0000)
		)
		(property "Sheetname" "FPGA Bank 16 & 17"
			(at 215.9 120.015 0)
			(effects
				(font
					(size 1.27 1.27)
				)
				(justify left bottom)
			)
		)
		(property "Sheetfile" "fpga-bank-16-17.kicad_sch"
			(at 215.9 203.7846 0)
			(effects
				(font
					(size 1.27 1.27)
				)
				(justify left top)
			)
		)
		(pin "USR_FLASH_1{SPI-FLASH}" bidirectional
			(at 247.65 155.575 0)
			(effects
				(font
					(size 1.27 1.27)
				)
				(justify right)
			)
		)
		(pin "USER_IO{USER-IO}" bidirectional
			(at 247.65 186.055 0)
			(effects
				(font
					(size 1.27 1.27)
				)
				(justify right)
			)
		)
		(pin "FMC{FMC-CTRL}" bidirectional
			(at 215.9 166.37 180)
			(effects
				(font
					(size 1.27 1.27)
				)
				(justify left)
			)
		)
		(pin "HDMI{HDMI}" bidirectional
			(at 215.9 198.12 180)
			(effects
				(font
					(size 1.27 1.27)
				)
				(justify left)
			)
		)
		(pin "USB_HOST{SPI-USB}" bidirectional
			(at 215.9 123.19 180)
			(effects
				(font
					(size 1.27 1.27)
				)
				(justify left)
			)
		)
		(pin "GBE_RGMII{RGMII}" bidirectional
			(at 215.9 195.58 180)
			(effects
				(font
					(size 1.27 1.27)
				)
				(justify left)
			)
		)
		(instances
			(project "k410t-devboard"
				(path ""
					(page "20")
				)
			)
		)
	)
	(sheet
		(at 101.6 185.42)
		(size 31.75 19.05)
		(exclude_from_sim no)
		(in_bom yes)
		(on_board yes)
		(dnp no)
		(fields_autoplaced yes)
		(stroke
			(width 0.1524)
			(type solid)
		)
		(fill
			(color 0 0 0 0.0000)
		)
		(property "Sheetname" "HDMI + Ethernet"
			(at 101.6 184.7084 0)
			(effects
				(font
					(size 1.27 1.27)
				)
				(justify left bottom)
			)
		)
		(property "Sheetfile" "hdmi-ethernet.kicad_sch"
			(at 101.6 205.0546 0)
			(effects
				(font
					(size 1.27 1.27)
				)
				(justify left top)
			)
		)
		(pin "HDMI{HDMI}" bidirectional
			(at 133.35 198.12 0)
			(effects
				(font
					(size 1.27 1.27)
				)
				(justify right)
			)
		)
		(pin "ETH_RMII{RMII}" bidirectional
			(at 133.35 187.96 0)
			(effects
				(font
					(size 1.27 1.27)
				)
				(justify right)
			)
		)
		(pin "POE_GBE{POE}" output
			(at 101.6 191.77 180)
			(effects
				(font
					(size 1.27 1.27)
				)
				(justify left)
			)
		)
		(pin "GBE_RGMII{RGMII}" bidirectional
			(at 133.35 195.58 0)
			(effects
				(font
					(size 1.27 1.27)
				)
				(justify right)
			)
		)
		(pin "POE_ETH{POE}" output
			(at 101.6 187.96 180)
			(effects
				(font
					(size 1.27 1.27)
				)
				(justify left)
			)
		)
		(instances
			(project "k410t-devboard"
				(path ""
					(page "13")
				)
			)
		)
	)
	(sheet
		(at 101.6 31.75)
		(size 31.75 19.05)
		(exclude_from_sim no)
		(in_bom yes)
		(on_board yes)
		(dnp no)
		(fields_autoplaced yes)
		(stroke
			(width 0.1524)
			(type solid)
		)
		(fill
			(color 0 0 0 0.0000)
		)
		(property "Sheetname" "DC-DC Converters"
			(at 101.6 31.0384 0)
			(effects
				(font
					(size 1.27 1.27)
				)
				(justify left bottom)
			)
		)
		(property "Sheetfile" "dc-dc.kicad_sch"
			(at 101.6 51.3846 0)
			(effects
				(font
					(size 1.27 1.27)
				)
				(justify left top)
			)
		)
		(pin "SUP_MCU{SUP-MCU}" bidirectional
			(at 133.35 38.1 0)
			(effects
				(font
					(size 1.27 1.27)
				)
				(justify right)
			)
		)
		(pin "POE_DC" input
			(at 101.6 46.99 180)
			(effects
				(font
					(size 1.27 1.27)
				)
				(justify left)
			)
		)
		(pin "PB_CTRL{PB-CTRL}" bidirectional
			(at 133.35 40.64 0)
			(effects
				(font
					(size 1.27 1.27)
				)
				(justify right)
			)
		)
		(pin "I2C{I2C}" bidirectional
			(at 133.35 35.56 0)
			(effects
				(font
					(size 1.27 1.27)
				)
				(justify right)
			)
		)
		(instances
			(project "k410t-devboard"
				(path ""
					(page "15")
				)
			)
		)
	)
	(sheet
		(at 333.375 107.315)
		(size 31.75 19.05)
		(exclude_from_sim no)
		(in_bom yes)
		(on_board yes)
		(dnp no)
		(fields_autoplaced yes)
		(stroke
			(width 0.1524)
			(type solid)
		)
		(fill
			(color 0 0 0 0.0000)
		)
		(property "Sheetname" "Supervisior MCU"
			(at 333.375 106.6034 0)
			(effects
				(font
					(size 1.27 1.27)
				)
				(justify left bottom)
			)
		)
		(property "Sheetfile" "supervisor-mcu.kicad_sch"
			(at 333.375 126.9496 0)
			(effects
				(font
					(size 1.27 1.27)
				)
				(justify left top)
			)
		)
		(pin "SUP_MCU{SUP-MCU}" bidirectional
			(at 333.375 111.125 180)
			(effects
				(font
					(size 1.27 1.27)
				)
				(justify left)
			)
		)
		(pin "I2C{I2C}" bidirectional
			(at 333.375 117.475 180)
			(effects
				(font
					(size 1.27 1.27)
				)
				(justify left)
			)
		)
		(instances
			(project "k410t-devboard"
				(path ""
					(page "24")
				)
			)
		)
	)
	(sheet
		(at 181.61 127)
		(size 31.75 24.765)
		(exclude_from_sim no)
		(in_bom yes)
		(on_board yes)
		(dnp no)
		(fields_autoplaced yes)
		(stroke
			(width 0.1524)
			(type solid)
		)
		(fill
			(color 0 0 0 0.0000)
		)
		(property "Sheetname" "FPGA Bank 18 & 32"
			(at 181.61 126.2884 0)
			(effects
				(font
					(size 1.27 1.27)
				)
				(justify left bottom)
			)
		)
		(property "Sheetfile" "fpga-bank-18-32.kicad_sch"
			(at 181.61 152.3496 0)
			(effects
				(font
					(size 1.27 1.27)
				)
				(justify left top)
			)
		)
		(pin "USB_USER{USB-FPGA-PHY}" bidirectional
			(at 181.61 130.175 180)
			(effects
				(font
					(size 1.27 1.27)
				)
				(justify left)
			)
		)
		(pin "ETH_RMII{RMII}" bidirectional
			(at 181.61 149.86 180)
			(effects
				(font
					(size 1.27 1.27)
				)
				(justify left)
			)
		)
		(pin "FMC{FMC-IO}" bidirectional
			(at 181.61 146.685 180)
			(effects
				(font
					(size 1.27 1.27)
				)
				(justify left)
			)
		)
		(instances
			(project "k410t-devboard"
				(path ""
					(page "23")
				)
			)
		)
	)
	(sheet
		(at 101.6 63.5)
		(size 31.75 22.86)
		(exclude_from_sim no)
		(in_bom yes)
		(on_board yes)
		(dnp no)
		(fields_autoplaced yes)
		(stroke
			(width 0.1524)
			(type solid)
		)
		(fill
			(color 0 0 0 0.0000)
		)
		(property "Sheetname" "User GPIO + LED + button + DIP switch"
			(at 101.6 62.7884 0)
			(effects
				(font
					(size 1.27 1.27)
				)
				(justify left bottom)
			)
		)
		(property "Sheetfile" "user-gpio.kicad_sch"
			(at 101.6 87.4526 0)
			(effects
				(font
					(size 1.27 1.27)
				)
				(justify left top)
			)
		)
		(pin "PMOD_A{PMOD}" bidirectional
			(at 133.35 71.12 0)
			(effects
				(font
					(size 1.27 1.27)
				)
				(justify right)
			)
		)
		(pin "PMOD_B{PMOD}" bidirectional
			(at 133.35 73.66 0)
			(effects
				(font
					(size 1.27 1.27)
				)
				(justify right)
			)
		)
		(pin "USER_IO{USER-IO}" bidirectional
			(at 133.35 84.455 0)
			(effects
				(font
					(size 1.27 1.27)
				)
				(justify right)
			)
		)
		(pin "CW_HEADER{CW-20PIN}" bidirectional
			(at 133.35 77.47 0)
			(effects
				(font
					(size 1.27 1.27)
				)
				(justify right)
			)
		)
		(pin "SUP_MCU{SUP-MCU}" bidirectional
			(at 133.35 67.31 0)
			(effects
				(font
					(size 1.27 1.27)
				)
				(justify right)
			)
		)
		(pin "FAN_PWM_CTRL" input
			(at 133.35 81.28 0)
			(effects
				(font
					(size 1.27 1.27)
				)
				(justify right)
			)
		)
		(instances
			(project "k410t-devboard"
				(path ""
					(page "11")
				)
			)
		)
	)
	(sheet
		(at 316.23 208.915)
		(size 31.75 21.59)
		(exclude_from_sim no)
		(in_bom yes)
		(on_board yes)
		(dnp no)
		(stroke
			(width 0.1524)
			(type solid)
		)
		(fill
			(color 0 0 0 0.0000)
		)
		(property "Sheetname" "Clocks"
			(at 316.23 207.645 0)
			(effects
				(font
					(size 1.27 1.27)
				)
				(justify left bottom)
			)
		)
		(property "Sheetfile" "clocks.kicad_sch"
			(at 316.23 230.505 0)
			(effects
				(font
					(size 1.27 1.27)
				)
				(justify left top)
			)
		)
		(pin "SYS{CLK}" output
			(at 316.23 217.805 180)
			(effects
				(font
					(size 1.27 1.27)
				)
				(justify left)
			)
		)
		(pin "LVDS_XO_200M_ENA" input
			(at 316.23 224.155 180)
			(effects
				(font
					(size 1.27 1.27)
				)
				(justify left)
			)
		)
		(pin "SUP_MCU{SUP-MCU}" bidirectional
			(at 316.23 227.965 180)
			(effects
				(font
					(size 1.27 1.27)
				)
				(justify left)
			)
		)
		(pin "I2C{I2C}" bidirectional
			(at 316.23 215.265 180)
			(effects
				(font
					(size 1.27 1.27)
				)
				(justify left)
			)
		)
		(pin "PLL{PLL-CLK}" output
			(at 316.23 221.615 180)
			(effects
				(font
					(size 1.27 1.27)
				)
				(justify left)
			)
		)
		(instances
			(project "k410t-devboard"
				(path ""
					(page "16")
				)
			)
		)
	)
	(sheet
		(at 181.61 170.18)
		(size 31.75 19.05)
		(exclude_from_sim no)
		(in_bom yes)
		(on_board yes)
		(dnp no)
		(fields_autoplaced yes)
		(stroke
			(width 0.1524)
			(type solid)
		)
		(fill
			(color 0 0 0 0.0000)
		)
		(property "Sheetname" "FPGA MGT Interface"
			(at 181.61 169.4684 0)
			(effects
				(font
					(size 1.27 1.27)
				)
				(justify left bottom)
			)
		)
		(property "Sheetfile" "fpga-mgt.kicad_sch"
			(at 181.61 189.8146 0)
			(effects
				(font
					(size 1.27 1.27)
				)
				(justify left top)
			)
		)
		(pin "GTX115{MGTX}" bidirectional
			(at 181.61 172.72 180)
			(effects
				(font
					(size 1.27 1.27)
				)
				(justify left)
			)
		)
		(pin "GTX116{MGTX}" bidirectional
			(at 181.61 175.26 180)
			(effects
				(font
					(size 1.27 1.27)
				)
				(justify left)
			)
		)
		(instances
			(project "k410t-devboard"
				(path ""
					(page "4")
				)
			)
		)
	)
	(sheet
		(at 316.23 170.18)
		(size 31.75 27.305)
		(exclude_from_sim no)
		(in_bom yes)
		(on_board yes)
		(dnp no)
		(fields_autoplaced yes)
		(stroke
			(width 0.1524)
			(type solid)
		)
		(fill
			(color 0 0 0 0.0000)
		)
		(property "Sheetname" "DRAM + SRAM"
			(at 316.23 169.4684 0)
			(effects
				(font
					(size 1.27 1.27)
				)
				(justify left bottom)
			)
		)
		(property "Sheetfile" "ram.kicad_sch"
			(at 316.23 198.0696 0)
			(effects
				(font
					(size 1.27 1.27)
				)
				(justify left top)
			)
		)
		(pin "DDR{DDR3_DRAM}" input
			(at 316.23 195.58 180)
			(effects
				(font
					(size 1.27 1.27)
				)
				(justify left)
			)
		)
		(pin "SRAM{SRAM}" input
			(at 316.23 174.625 180)
			(effects
				(font
					(size 1.27 1.27)
				)
				(justify left)
			)
		)
		(instances
			(project "k410t-devboard"
				(path ""
					(page "8")
				)
			)
		)
	)
	(sheet
		(at 38.1 31.75)
		(size 31.75 19.05)
		(exclude_from_sim no)
		(in_bom yes)
		(on_board yes)
		(dnp no)
		(fields_autoplaced yes)
		(stroke
			(width 0.1524)
			(type solid)
		)
		(fill
			(color 0 0 0 0.0000)
		)
		(property "Sheetname" "Power supply"
			(at 38.1 31.0384 0)
			(effects
				(font
					(size 1.27 1.27)
				)
				(justify left bottom)
			)
		)
		(property "Sheetfile" "power-supply.kicad_sch"
			(at 38.1 51.3846 0)
			(effects
				(font
					(size 1.27 1.27)
				)
				(justify left top)
			)
		)
		(pin "USB_DBG_PD{USB-C-PD}" bidirectional
			(at 38.1 49.53 180)
			(effects
				(font
					(size 1.27 1.27)
				)
				(justify left)
			)
		)
		(pin "PD_CTRL{STUSB4500}" bidirectional
			(at 69.85 39.37 0)
			(effects
				(font
					(size 1.27 1.27)
				)
				(justify right)
			)
		)
		(pin "POE_ETH{POE}" input
			(at 38.1 46.99 180)
			(effects
				(font
					(size 1.27 1.27)
				)
				(justify left)
			)
		)
		(pin "POE_GBE{POE}" input
			(at 38.1 44.45 180)
			(effects
				(font
					(size 1.27 1.27)
				)
				(justify left)
			)
		)
		(pin "SUP_MCU{SUP-MCU}" bidirectional
			(at 69.85 36.83 0)
			(effects
				(font
					(size 1.27 1.27)
				)
				(justify right)
			)
		)
		(pin "POE_DC" output
			(at 69.85 46.99 0)
			(effects
				(font
					(size 1.27 1.27)
				)
				(justify right)
			)
		)
		(pin "I2C{I2C}" bidirectional
			(at 69.85 34.29 0)
			(effects
				(font
					(size 1.27 1.27)
				)
				(justify right)
			)
		)
		(instances
			(project "k410t-devboard"
				(path ""
					(page "9")
				)
			)
		)
	)
	(sheet_instances
		(path "/"
			(page "1")
		)
	)
)
